(kicad_pcb
	(version 20260206)
	(generator "pcbnew")
	(generator_version "10.0")
	(general
		(thickness 1.6)
		(legacy_teardrops no)
	)
	(paper "A4")
	(title_block
		(title "01162023_DA0F0TEBIF0_F0T_Expander_BD_F_brd_V02_OCP.brd")
		(comment 1 "Grand Teton / footprints 3288-3294 of 9728")
	)
	(layers
		(0 "F.Cu" signal "TOP")
		(4 "In1.Cu" signal "GND")
		(6 "In2.Cu" signal "VCC")
		(8 "In3.Cu" signal "VCC1")
		(10 "In4.Cu" signal "GND1")
		(12 "In5.Cu" signal "IN1")
		(14 "In6.Cu" signal "GND2")
		(16 "In7.Cu" signal "IN2")
		(18 "In8.Cu" signal "GND3")
		(20 "In9.Cu" signal "IN3")
		(22 "In10.Cu" signal "GND4")
		(24 "In11.Cu" signal "IN4")
		(26 "In12.Cu" signal "GND5")
		(28 "In13.Cu" signal "IN5")
		(30 "In14.Cu" signal "GND6")
		(32 "In15.Cu" signal "IN6")
		(34 "In16.Cu" signal "GND7")
		(2 "B.Cu" signal "BOTTOM")
		(9 "F.Adhes" user "F.Adhesive")
		(11 "B.Adhes" user "B.Adhesive")
		(13 "F.Paste" user "Package Geometry/Pastemask Top")
		(15 "B.Paste" user "Package Geometry/Pastemask Bottom")
		(5 "F.SilkS" user "Ref Des/Silkscreen Top")
		(7 "B.SilkS" user "Ref Des/Silkscreen Bottom")
		(1 "F.Mask" user "Board Geometry/Soldermask Top")
		(3 "B.Mask" user "Board Geometry/Soldermask Bottom")
		(17 "Dwgs.User" user "User.Drawings")
		(19 "Cmts.User" user "User.Comments")
		(21 "Eco1.User" user "User.Eco1")
		(23 "Eco2.User" user "User.Eco2")
		(25 "Edge.Cuts" user "Board Geometry/Outline")
		(27 "Margin" user)
		(31 "F.CrtYd" user "Package Geometry/Place Bound Top")
		(29 "B.CrtYd" user "Package Geometry/Place Bound Bottom")
		(35 "F.Fab" user "Ref Des/Assembly Top")
		(33 "B.Fab" user "Ref Des/Assembly Bottom")
	)
	(footprint ""
		(layer "F.Cu")
		(at 314.861448 -124.991114 180)
		(property "Reference" "C447"
			(at 0 0 180)
			(layer "F.SilkS")
			(hide yes)
			(effects
				(font
					(size 1.27 1.27)
				)
			)
		)
		(property "Value" ""
			(at 0 0 180)
			(layer "F.Fab")
			(effects
				(font
					(size 1.27 1.27)
				)
			)
		)
		(duplicate_pad_numbers_are_jumpers no)
		(fp_line
			(start 0.299974 0.150114)
			(end -0.299974 0.150114)
			(stroke
				(width 0.1)
				(type default)
			)
			(layer "F.Fab")
		)
		(fp_line
			(start 0.299974 -0.150114)
			(end 0.299974 0.150114)
			(stroke
				(width 0.1)
				(type default)
			)
			(layer "F.Fab")
		)
		(fp_line
			(start -0.299974 0.150114)
			(end -0.299974 -0.150114)
			(stroke
				(width 0.1)
				(type default)
			)
			(layer "F.Fab")
		)
		(fp_line
			(start -0.299974 -0.150114)
			(end 0.299974 -0.150114)
			(stroke
				(width 0.1)
				(type default)
			)
			(layer "F.Fab")
		)
		(pad "1" smd rect
			(at -0.2667 0 180)
			(size 0.3048 0.381)
			(layers "F.Cu" "F.Mask" "F.Paste")
			(net "P5E_PEX2_STN0_TX_DP<3>")
		)
		(pad "2" smd rect
			(at 0.2667 0 180)
			(size 0.3048 0.381)
			(layers "F.Cu" "F.Mask" "F.Paste")
			(net "P5E_PEX2_STN0_TX_C_DP<3>")
		)
	)
	(footprint ""
		(layer "F.Cu")
		(at 257.177032 -343.843356 180)
		(property "Reference" "C4492"
			(at 0 0 180)
			(layer "F.SilkS")
			(hide yes)
			(effects
				(font
					(size 1.27 1.27)
				)
			)
		)
		(property "Value" ""
			(at 0 0 180)
			(layer "F.Fab")
			(effects
				(font
					(size 1.27 1.27)
				)
			)
		)
		(duplicate_pad_numbers_are_jumpers no)
		(fp_line
			(start 0.7874 0.4064)
			(end -0.7874 0.4064)
			(stroke
				(width 0.1524)
				(type default)
			)
			(layer "F.SilkS")
		)
		(fp_line
			(start 0.7874 -0.4064)
			(end 0.7874 0.4064)
			(stroke
				(width 0.1524)
				(type default)
			)
			(layer "F.SilkS")
		)
		(fp_line
			(start -0.7874 0.4064)
			(end -0.7874 -0.4064)
			(stroke
				(width 0.1524)
				(type default)
			)
			(layer "F.SilkS")
		)
		(fp_line
			(start -0.7874 -0.4064)
			(end 0.7874 -0.4064)
			(stroke
				(width 0.1524)
				(type default)
			)
			(layer "F.SilkS")
		)
		(fp_line
			(start 0.67945 0.3048)
			(end 0.120396 0.3048)
			(stroke
				(width 0.1)
				(type default)
			)
			(layer "F.Fab")
		)
		(fp_line
			(start 0.67945 -0.3048)
			(end 0.67945 0.3048)
			(stroke
				(width 0.1)
				(type default)
			)
			(layer "F.Fab")
		)
		(fp_line
			(start 0.12065 -0.2794)
			(end 0.12065 -0.3048)
			(stroke
				(width 0.1)
				(type default)
			)
			(layer "F.Fab")
		)
		(fp_line
			(start 0.12065 -0.3048)
			(end 0.67945 -0.3048)
			(stroke
				(width 0.1)
				(type default)
			)
			(layer "F.Fab")
		)
		(fp_line
			(start 0.120396 0.3048)
			(end 0.120396 0.2794)
			(stroke
				(width 0.1)
				(type default)
			)
			(layer "F.Fab")
		)
		(fp_line
			(start 0.120396 0.2794)
			(end -0.12065 0.2794)
			(stroke
				(width 0.1)
				(type default)
			)
			(layer "F.Fab")
		)
		(fp_line
			(start -0.12065 0.3048)
			(end -0.67945 0.3048)
			(stroke
				(width 0.1)
				(type default)
			)
			(layer "F.Fab")
		)
		(fp_line
			(start -0.12065 0.2794)
			(end -0.12065 0.3048)
			(stroke
				(width 0.1)
				(type default)
			)
			(layer "F.Fab")
		)
		(fp_line
			(start -0.12065 -0.2794)
			(end 0.12065 -0.2794)
			(stroke
				(width 0.1)
				(type default)
			)
			(layer "F.Fab")
		)
		(fp_line
			(start -0.12065 -0.305054)
			(end -0.12065 -0.2794)
			(stroke
				(width 0.1)
				(type default)
			)
			(layer "F.Fab")
		)
		(fp_line
			(start -0.67945 0.3048)
			(end -0.67945 -0.305054)
			(stroke
				(width 0.1)
				(type default)
			)
			(layer "F.Fab")
		)
		(fp_line
			(start -0.67945 -0.305054)
			(end -0.12065 -0.305054)
			(stroke
				(width 0.1)
				(type default)
			)
			(layer "F.Fab")
		)
		(pad "1" smd circle
			(at -0.40005 0 180)
			(size 0 0)
			(layers "F.Cu" "F.Mask" "F.Paste")
			(net "HSC_OC_LT6700_VS")
		)
		(pad "2" smd circle
			(at 0.40005 0 180)
			(size 0 0)
			(layers "F.Cu" "F.Mask" "F.Paste")
			(net "GND")
		)
	)
	(footprint ""
		(layer "F.Cu")
		(at 47.530512 -66.32194 -90)
		(property "Reference" "PC647"
			(at 0 0 270)
			(layer "F.SilkS")
			(hide yes)
			(effects
				(font
					(size 1.27 1.27)
				)
			)
		)
		(property "Value" ""
			(at 0 0 270)
			(layer "F.Fab")
			(effects
				(font
					(size 1.27 1.27)
				)
			)
		)
		(duplicate_pad_numbers_are_jumpers no)
		(fp_line
			(start -0.7874 0.4064)
			(end -0.7874 -0.4064)
			(stroke
				(width 0.1524)
				(type default)
			)
			(layer "F.SilkS")
		)
		(fp_line
			(start 0.7874 0.4064)
			(end -0.7874 0.4064)
			(stroke
				(width 0.1524)
				(type default)
			)
			(layer "F.SilkS")
		)
		(fp_line
			(start -0.7874 -0.4064)
			(end 0.7874 -0.4064)
			(stroke
				(width 0.1524)
				(type default)
			)
			(layer "F.SilkS")
		)
		(fp_line
			(start 0.7874 -0.4064)
			(end 0.7874 0.4064)
			(stroke
				(width 0.1524)
				(type default)
			)
			(layer "F.SilkS")
		)
		(fp_line
			(start -0.67945 0.3048)
			(end -0.67945 -0.305054)
			(stroke
				(width 0.1)
				(type default)
			)
			(layer "F.Fab")
		)
		(fp_line
			(start -0.12065 0.3048)
			(end -0.67945 0.3048)
			(stroke
				(width 0.1)
				(type default)
			)
			(layer "F.Fab")
		)
		(fp_line
			(start 0.120396 0.3048)
			(end 0.120396 0.2794)
			(stroke
				(width 0.1)
				(type default)
			)
			(layer "F.Fab")
		)
		(fp_line
			(start 0.67945 0.3048)
			(end 0.120396 0.3048)
			(stroke
				(width 0.1)
				(type default)
			)
			(layer "F.Fab")
		)
		(fp_line
			(start -0.12065 0.2794)
			(end -0.12065 0.3048)
			(stroke
				(width 0.1)
				(type default)
			)
			(layer "F.Fab")
		)
		(fp_line
			(start 0.120396 0.2794)
			(end -0.12065 0.2794)
			(stroke
				(width 0.1)
				(type default)
			)
			(layer "F.Fab")
		)
		(fp_line
			(start -0.12065 -0.2794)
			(end 0.12065 -0.2794)
			(stroke
				(width 0.1)
				(type default)
			)
			(layer "F.Fab")
		)
		(fp_line
			(start 0.12065 -0.2794)
			(end 0.12065 -0.3048)
			(stroke
				(width 0.1)
				(type default)
			)
			(layer "F.Fab")
		)
		(fp_line
			(start 0.12065 -0.3048)
			(end 0.67945 -0.3048)
			(stroke
				(width 0.1)
				(type default)
			)
			(layer "F.Fab")
		)
		(fp_line
			(start 0.67945 -0.3048)
			(end 0.67945 0.3048)
			(stroke
				(width 0.1)
				(type default)
			)
			(layer "F.Fab")
		)
		(fp_line
			(start -0.67945 -0.305054)
			(end -0.12065 -0.305054)
			(stroke
				(width 0.1)
				(type default)
			)
			(layer "F.Fab")
		)
		(fp_line
			(start -0.12065 -0.305054)
			(end -0.12065 -0.2794)
			(stroke
				(width 0.1)
				(type default)
			)
			(layer "F.Fab")
		)
		(pad "1" smd circle
			(at -0.40005 0 270)
			(size 0 0)
			(layers "F.Cu" "F.Mask" "F.Paste")
			(net "P12V_SSD1_CO_DV_DT")
		)
		(pad "2" smd circle
			(at 0.40005 0 270)
			(size 0 0)
			(layers "F.Cu" "F.Mask" "F.Paste")
			(net "GND")
		)
	)
	(footprint ""
		(layer "F.Cu")
		(at 112.311942 -111.531654)
		(property "Reference" "PR6876"
			(at 0 0 0)
			(layer "F.SilkS")
			(hide yes)
			(effects
				(font
					(size 1.27 1.27)
				)
			)
		)
		(property "Value" ""
			(at 0 0 0)
			(layer "F.Fab")
			(effects
				(font
					(size 1.27 1.27)
				)
			)
		)
		(duplicate_pad_numbers_are_jumpers no)
		(fp_line
			(start -0.7874 -0.4064)
			(end 0.7874 -0.4064)
			(stroke
				(width 0.1524)
				(type default)
			)
			(layer "F.SilkS")
		)
		(fp_line
			(start -0.7874 0.4064)
			(end -0.7874 -0.4064)
			(stroke
				(width 0.1524)
				(type default)
			)
			(layer "F.SilkS")
		)
		(fp_line
			(start 0.7874 -0.4064)
			(end 0.7874 0.4064)
			(stroke
				(width 0.1524)
				(type default)
			)
			(layer "F.SilkS")
		)
		(fp_line
			(start 0.7874 0.4064)
			(end -0.7874 0.4064)
			(stroke
				(width 0.1524)
				(type default)
			)
			(layer "F.SilkS")
		)
		(fp_line
			(start -0.67945 -0.305054)
			(end -0.12065 -0.305054)
			(stroke
				(width 0.1)
				(type default)
			)
			(layer "F.Fab")
		)
		(fp_line
			(start -0.67945 0.3048)
			(end -0.67945 -0.305054)
			(stroke
				(width 0.1)
				(type default)
			)
			(layer "F.Fab")
		)
		(fp_line
			(start -0.12065 -0.305054)
			(end -0.12065 -0.2794)
			(stroke
				(width 0.1)
				(type default)
			)
			(layer "F.Fab")
		)
		(fp_line
			(start -0.12065 -0.2794)
			(end 0.12065 -0.2794)
			(stroke
				(width 0.1)
				(type default)
			)
			(layer "F.Fab")
		)
		(fp_line
			(start -0.12065 0.2794)
			(end -0.12065 0.3048)
			(stroke
				(width 0.1)
				(type default)
			)
			(layer "F.Fab")
		)
		(fp_line
			(start -0.12065 0.3048)
			(end -0.67945 0.3048)
			(stroke
				(width 0.1)
				(type default)
			)
			(layer "F.Fab")
		)
		(fp_line
			(start 0.120396 0.2794)
			(end -0.12065 0.2794)
			(stroke
				(width 0.1)
				(type default)
			)
			(layer "F.Fab")
		)
		(fp_line
			(start 0.120396 0.3048)
			(end 0.120396 0.2794)
			(stroke
				(width 0.1)
				(type default)
			)
			(layer "F.Fab")
		)
		(fp_line
			(start 0.12065 -0.3048)
			(end 0.67945 -0.3048)
			(stroke
				(width 0.1)
				(type default)
			)
			(layer "F.Fab")
		)
		(fp_line
			(start 0.12065 -0.2794)
			(end 0.12065 -0.3048)
			(stroke
				(width 0.1)
				(type default)
			)
			(layer "F.Fab")
		)
		(fp_line
			(start 0.67945 -0.3048)
			(end 0.67945 0.3048)
			(stroke
				(width 0.1)
				(type default)
			)
			(layer "F.Fab")
		)
		(fp_line
			(start 0.67945 0.3048)
			(end 0.120396 0.3048)
			(stroke
				(width 0.1)
				(type default)
			)
			(layer "F.Fab")
		)
		(pad "1" smd circle
			(at -0.40005 0)
			(size 0 0)
			(layers "F.Cu" "F.Mask" "F.Paste")
			(net "P12V_NIC1_CO_ISET")
		)
		(pad "2" smd circle
			(at 0.40005 0)
			(size 0 0)
			(layers "F.Cu" "F.Mask" "F.Paste")
			(net "GND")
		)
	)
	(footprint ""
		(layer "F.Cu")
		(at 334.838548 -80.607662 90)
		(property "Reference" "R1170"
			(at 0 0 90)
			(layer "F.SilkS")
			(hide yes)
			(effects
				(font
					(size 1.27 1.27)
				)
			)
		)
		(property "Value" ""
			(at 0 0 90)
			(layer "F.Fab")
			(effects
				(font
					(size 1.27 1.27)
				)
			)
		)
		(duplicate_pad_numbers_are_jumpers no)
		(fp_line
			(start -0.7874 -0.4064)
			(end 0.7874 -0.4064)
			(stroke
				(width 0.1524)
				(type default)
			)
			(layer "F.SilkS")
		)
		(fp_line
			(start -0.12065 -0.305054)
			(end -0.12065 -0.2794)
			(stroke
				(width 0.1)
				(type default)
			)
			(layer "F.Fab")
		)
		(fp_line
			(start -0.67945 -0.305054)
			(end -0.12065 -0.305054)
			(stroke
				(width 0.1)
				(type default)
			)
			(layer "F.Fab")
		)
		(fp_line
			(start 0.67945 -0.3048)
			(end 0.67945 0.3048)
			(stroke
				(width 0.1)
				(type default)
			)
			(layer "F.Fab")
		)
		(fp_line
			(start 0.12065 -0.3048)
			(end 0.67945 -0.3048)
			(stroke
				(width 0.1)
				(type default)
			)
			(layer "F.Fab")
		)
		(fp_line
			(start 0.12065 -0.2794)
			(end 0.12065 -0.3048)
			(stroke
				(width 0.1)
				(type default)
			)
			(layer "F.Fab")
		)
		(fp_line
			(start -0.12065 -0.2794)
			(end 0.12065 -0.2794)
			(stroke
				(width 0.1)
				(type default)
			)
			(layer "F.Fab")
		)
		(fp_line
			(start 0.120396 0.2794)
			(end -0.12065 0.2794)
			(stroke
				(width 0.1)
				(type default)
			)
			(layer "F.Fab")
		)
		(fp_line
			(start -0.12065 0.2794)
			(end -0.12065 0.3048)
			(stroke
				(width 0.1)
				(type default)
			)
			(layer "F.Fab")
		)
		(fp_line
			(start 0.67945 0.3048)
			(end 0.120396 0.3048)
			(stroke
				(width 0.1)
				(type default)
			)
			(layer "F.Fab")
		)
		(fp_line
			(start 0.120396 0.3048)
			(end 0.120396 0.2794)
			(stroke
				(width 0.1)
				(type default)
			)
			(layer "F.Fab")
		)
		(fp_line
			(start -0.12065 0.3048)
			(end -0.67945 0.3048)
			(stroke
				(width 0.1)
				(type default)
			)
			(layer "F.Fab")
		)
		(fp_line
			(start -0.67945 0.3048)
			(end -0.67945 -0.305054)
			(stroke
				(width 0.1)
				(type default)
			)
			(layer "F.Fab")
		)
		(pad "1" smd circle
			(at -0.40005 0 90)
			(size 0 0)
			(layers "F.Cu" "F.Mask" "F.Paste")
			(net "CLK_100M_DB800ZL_SSD8_R_DP")
		)
		(pad "2" smd circle
			(at 0.40005 0 90)
			(size 0 0)
			(layers "F.Cu" "F.Mask" "F.Paste")
			(net "CLK_100M_DB800ZL_SSD8_DP")
		)
	)
	(footprint ""
		(layer "F.Cu")
		(at 52.267104 -57.332626)
		(property "Reference" "R6840"
			(at 0 0 0)
			(layer "F.SilkS")
			(hide yes)
			(effects
				(font
					(size 1.27 1.27)
				)
			)
		)
		(property "Value" ""
			(at 0 0 0)
			(layer "F.Fab")
			(effects
				(font
					(size 1.27 1.27)
				)
			)
		)
		(duplicate_pad_numbers_are_jumpers no)
		(fp_line
			(start -0.7874 -0.4064)
			(end 0.7874 -0.4064)
			(stroke
				(width 0.1524)
				(type default)
			)
			(layer "F.SilkS")
		)
		(fp_line
			(start -0.7874 0.4064)
			(end -0.7874 -0.4064)
			(stroke
				(width 0.1524)
				(type default)
			)
			(layer "F.SilkS")
		)
		(fp_line
			(start 0.7874 -0.4064)
			(end 0.7874 0.4064)
			(stroke
				(width 0.1524)
				(type default)
			)
			(layer "F.SilkS")
		)
		(fp_line
			(start 0.7874 0.4064)
			(end -0.7874 0.4064)
			(stroke
				(width 0.1524)
				(type default)
			)
			(layer "F.SilkS")
		)
		(fp_line
			(start -0.67945 -0.305054)
			(end -0.12065 -0.305054)
			(stroke
				(width 0.1)
				(type default)
			)
			(layer "F.Fab")
		)
		(fp_line
			(start -0.67945 0.3048)
			(end -0.67945 -0.305054)
			(stroke
				(width 0.1)
				(type default)
			)
			(layer "F.Fab")
		)
		(fp_line
			(start -0.12065 -0.305054)
			(end -0.12065 -0.2794)
			(stroke
				(width 0.1)
				(type default)
			)
			(layer "F.Fab")
		)
		(fp_line
			(start -0.12065 -0.2794)
			(end 0.12065 -0.2794)
			(stroke
				(width 0.1)
				(type default)
			)
			(layer "F.Fab")
		)
		(fp_line
			(start -0.12065 0.2794)
			(end -0.12065 0.3048)
			(stroke
				(width 0.1)
				(type default)
			)
			(layer "F.Fab")
		)
		(fp_line
			(start -0.12065 0.3048)
			(end -0.67945 0.3048)
			(stroke
				(width 0.1)
				(type default)
			)
			(layer "F.Fab")
		)
		(fp_line
			(start 0.120396 0.2794)
			(end -0.12065 0.2794)
			(stroke
				(width 0.1)
				(type default)
			)
			(layer "F.Fab")
		)
		(fp_line
			(start 0.120396 0.3048)
			(end 0.120396 0.2794)
			(stroke
				(width 0.1)
				(type default)
			)
			(layer "F.Fab")
		)
		(fp_line
			(start 0.12065 -0.3048)
			(end 0.67945 -0.3048)
			(stroke
				(width 0.1)
				(type default)
			)
			(layer "F.Fab")
		)
		(fp_line
			(start 0.12065 -0.2794)
			(end 0.12065 -0.3048)
			(stroke
				(width 0.1)
				(type default)
			)
			(layer "F.Fab")
		)
		(fp_line
			(start 0.67945 -0.3048)
			(end 0.67945 0.3048)
			(stroke
				(width 0.1)
				(type default)
			)
			(layer "F.Fab")
		)
		(fp_line
			(start 0.67945 0.3048)
			(end 0.120396 0.3048)
			(stroke
				(width 0.1)
				(type default)
			)
			(layer "F.Fab")
		)
		(pad "1" smd circle
			(at -0.40005 0)
			(size 0 0)
			(layers "F.Cu" "F.Mask" "F.Paste")
			(net "SSD1_PWR_EN_R")
		)
		(pad "2" smd circle
			(at 0.40005 0)
			(size 0 0)
			(layers "F.Cu" "F.Mask" "F.Paste")
			(net "GND")
		)
	)
	(footprint ""
		(layer "F.Cu")
		(at 452.277734 -286.034988 180)
		(property "Reference" "PC278"
			(at 0 0 180)
			(layer "F.SilkS")
			(hide yes)
			(effects
				(font
					(size 1.27 1.27)
				)
			)
		)
		(property "Value" ""
			(at 0 0 180)
			(layer "F.Fab")
			(effects
				(font
					(size 1.27 1.27)
				)
			)
		)
		(duplicate_pad_numbers_are_jumpers no)
		(fp_line
			(start 2.750058 2.750058)
			(end 2.750058 0.9398)
			(stroke
				(width 0.1524)
				(type default)
			)
			(layer "F.SilkS")
		)
		(fp_line
			(start 2.750058 -0.9398)
			(end 2.750058 -2.750058)
			(stroke
				(width 0.1524)
				(type default)
			)
			(layer "F.SilkS")
		)
		(fp_line
			(start 2.750058 -2.750058)
			(end -1.988058 -2.750058)
			(stroke
				(width 0.1524)
				(type default)
			)
			(layer "F.SilkS")
		)
		(fp_line
			(start -1.988058 2.750058)
			(end 2.750058 2.750058)
			(stroke
				(width 0.1524)
				(type default)
			)
			(layer "F.SilkS")
		)
		(fp_line
			(start -1.988058 -2.750058)
			(end -2.750058 -1.988058)
			(stroke
				(width 0.1524)
				(type default)
			)
			(layer "F.SilkS")
		)
		(fp_line
			(start -2.750058 1.988058)
			(end -1.988058 2.750058)
			(stroke
				(width 0.1524)
				(type default)
			)
			(layer "F.SilkS")
		)
		(fp_line
			(start -2.750058 0.9398)
			(end -2.750058 1.988058)
			(stroke
				(width 0.1524)
				(type default)
			)
			(layer "F.SilkS")
		)
		(fp_line
			(start -2.750058 -1.988058)
			(end -2.750058 -0.9398)
			(stroke
				(width 0.1524)
				(type default)
			)
			(layer "F.SilkS")
		)
		(fp_line
			(start 2.750058 2.750058)
			(end 2.750058 -2.750058)
			(stroke
				(width 0.1)
				(type default)
			)
			(layer "F.Fab")
		)
		(fp_line
			(start 2.750058 -2.750058)
			(end -2.750058 -2.750058)
			(stroke
				(width 0.1)
				(type default)
			)
			(layer "F.Fab")
		)
		(fp_line
			(start -2.750058 2.750058)
			(end 2.750058 2.750058)
			(stroke
				(width 0.1)
				(type default)
			)
			(layer "F.Fab")
		)
		(fp_line
			(start -2.750058 -2.750058)
			(end -2.750058 2.750058)
			(stroke
				(width 0.1)
				(type default)
			)
			(layer "F.Fab")
		)
		(pad "1" smd rect
			(at -2.199894 0 270)
			(size 1.6002 3.0226)
			(layers "F.Cu" "F.Mask" "F.Paste")
			(net "P1V25_PEX3_R")
		)
		(pad "2" smd rect
			(at 2.199894 0 270)
			(size 1.6002 3.0226)
			(layers "F.Cu" "F.Mask" "F.Paste")
			(net "GND")
		)
	)
)
